# BARRELEYE_G2-MB-PVT-X04-HW-BOM-X26_20180122_Final.xls.xlsx — POP_GA (bom)
| FOXCONN TECHNOLOGY GROUP |  |  |  |  |  |  |  |  |  |  |  |  |
| BILL OF MATERIAL |  |  |  |  |  |  |  |  |  |  |  |  |
| REV OF  BOM |  | CUSTOMER | RACKSPACE |  | CUSTOMER P/N |  | PRODUCT CODE |  | PWA  REV |  | DATE |  |
| Sourcing (Single/Sole/Multi) | Critical Commodity (Y or N) | Component Class (1, 2, other) | Customer PSL (Y or N) | Item Number | Foxconn P/N | Customer P/N | Part Description | Manufacturer  Full Name | Manufacturer  Part Number | Qty | RoHS Status | Location |
